(kicad_pcb
	(version 20260206)
	(generator "pcbnew")
	(generator_version "10.0")
	(general
		(thickness 1.6)
		(legacy_teardrops no)
	)
	(paper "A4")
	(title_block
		(title "01162023_DA0F0TEBIF0_F0T_Expander_BD_F_brd_V02_OCP.brd")
		(comment 1 "Grand Teton / footprints 4257-4263 of 9728")
	)
	(layers
		(0 "F.Cu" signal "TOP")
		(4 "In1.Cu" signal "GND")
		(6 "In2.Cu" signal "VCC")
		(8 "In3.Cu" signal "VCC1")
		(10 "In4.Cu" signal "GND1")
		(12 "In5.Cu" signal "IN1")
		(14 "In6.Cu" signal "GND2")
		(16 "In7.Cu" signal "IN2")
		(18 "In8.Cu" signal "GND3")
		(20 "In9.Cu" signal "IN3")
		(22 "In10.Cu" signal "GND4")
		(24 "In11.Cu" signal "IN4")
		(26 "In12.Cu" signal "GND5")
		(28 "In13.Cu" signal "IN5")
		(30 "In14.Cu" signal "GND6")
		(32 "In15.Cu" signal "IN6")
		(34 "In16.Cu" signal "GND7")
		(2 "B.Cu" signal "BOTTOM")
		(9 "F.Adhes" user "F.Adhesive")
		(11 "B.Adhes" user "B.Adhesive")
		(13 "F.Paste" user "Package Geometry/Pastemask Top")
		(15 "B.Paste" user "Package Geometry/Pastemask Bottom")
		(5 "F.SilkS" user "Ref Des/Silkscreen Top")
		(7 "B.SilkS" user "Ref Des/Silkscreen Bottom")
		(1 "F.Mask" user "Board Geometry/Soldermask Top")
		(3 "B.Mask" user "Board Geometry/Soldermask Bottom")
		(17 "Dwgs.User" user "User.Drawings")
		(19 "Cmts.User" user "User.Comments")
		(21 "Eco1.User" user "User.Eco1")
		(23 "Eco2.User" user "User.Eco2")
		(25 "Edge.Cuts" user "Board Geometry/Outline")
		(27 "Margin" user)
		(31 "F.CrtYd" user "Package Geometry/Place Bound Top")
		(29 "B.CrtYd" user "Package Geometry/Place Bound Bottom")
		(35 "F.Fab" user "Ref Des/Assembly Top")
		(33 "B.Fab" user "Ref Des/Assembly Bottom")
	)
	(footprint ""
		(layer "F.Cu")
		(at 21.917914 -413.969708 90)
		(property "Reference" "R5592"
			(at 0 0 90)
			(layer "F.SilkS")
			(hide yes)
			(effects
				(font
					(size 1.27 1.27)
				)
			)
		)
		(property "Value" ""
			(at 0 0 90)
			(layer "F.Fab")
			(effects
				(font
					(size 1.27 1.27)
				)
			)
		)
		(duplicate_pad_numbers_are_jumpers no)
		(fp_line
			(start 0.7874 -0.4064)
			(end 0.7874 0.4064)
			(stroke
				(width 0.1524)
				(type default)
			)
			(layer "F.SilkS")
		)
		(fp_line
			(start -0.7874 -0.4064)
			(end 0.7874 -0.4064)
			(stroke
				(width 0.1524)
				(type default)
			)
			(layer "F.SilkS")
		)
		(fp_line
			(start 0.7874 0.4064)
			(end -0.7874 0.4064)
			(stroke
				(width 0.1524)
				(type default)
			)
			(layer "F.SilkS")
		)
		(fp_line
			(start -0.7874 0.4064)
			(end -0.7874 -0.4064)
			(stroke
				(width 0.1524)
				(type default)
			)
			(layer "F.SilkS")
		)
		(fp_line
			(start -0.12065 -0.305054)
			(end -0.12065 -0.2794)
			(stroke
				(width 0.1)
				(type default)
			)
			(layer "F.Fab")
		)
		(fp_line
			(start -0.67945 -0.305054)
			(end -0.12065 -0.305054)
			(stroke
				(width 0.1)
				(type default)
			)
			(layer "F.Fab")
		)
		(fp_line
			(start 0.67945 -0.3048)
			(end 0.67945 0.3048)
			(stroke
				(width 0.1)
				(type default)
			)
			(layer "F.Fab")
		)
		(fp_line
			(start 0.12065 -0.3048)
			(end 0.67945 -0.3048)
			(stroke
				(width 0.1)
				(type default)
			)
			(layer "F.Fab")
		)
		(fp_line
			(start 0.12065 -0.2794)
			(end 0.12065 -0.3048)
			(stroke
				(width 0.1)
				(type default)
			)
			(layer "F.Fab")
		)
		(fp_line
			(start -0.12065 -0.2794)
			(end 0.12065 -0.2794)
			(stroke
				(width 0.1)
				(type default)
			)
			(layer "F.Fab")
		)
		(fp_line
			(start 0.120396 0.2794)
			(end -0.12065 0.2794)
			(stroke
				(width 0.1)
				(type default)
			)
			(layer "F.Fab")
		)
		(fp_line
			(start -0.12065 0.2794)
			(end -0.12065 0.3048)
			(stroke
				(width 0.1)
				(type default)
			)
			(layer "F.Fab")
		)
		(fp_line
			(start 0.67945 0.3048)
			(end 0.120396 0.3048)
			(stroke
				(width 0.1)
				(type default)
			)
			(layer "F.Fab")
		)
		(fp_line
			(start 0.120396 0.3048)
			(end 0.120396 0.2794)
			(stroke
				(width 0.1)
				(type default)
			)
			(layer "F.Fab")
		)
		(fp_line
			(start -0.12065 0.3048)
			(end -0.67945 0.3048)
			(stroke
				(width 0.1)
				(type default)
			)
			(layer "F.Fab")
		)
		(fp_line
			(start -0.67945 0.3048)
			(end -0.67945 -0.305054)
			(stroke
				(width 0.1)
				(type default)
			)
			(layer "F.Fab")
		)
		(pad "1" smd circle
			(at -0.40005 0 90)
			(size 0 0)
			(layers "F.Cu" "F.Mask" "F.Paste")
			(net "LM75_0_A2")
		)
		(pad "2" smd circle
			(at 0.40005 0 90)
			(size 0 0)
			(layers "F.Cu" "F.Mask" "F.Paste")
			(net "GND")
		)
	)
	(footprint ""
		(layer "F.Cu")
		(at 121.756424 -61.487812 180)
		(property "Reference" "R5972"
			(at 0 0 180)
			(layer "F.SilkS")
			(hide yes)
			(effects
				(font
					(size 1.27 1.27)
				)
			)
		)
		(property "Value" ""
			(at 0 0 180)
			(layer "F.Fab")
			(effects
				(font
					(size 1.27 1.27)
				)
			)
		)
		(duplicate_pad_numbers_are_jumpers no)
		(fp_line
			(start 0.7874 0.4064)
			(end -0.7874 0.4064)
			(stroke
				(width 0.1524)
				(type default)
			)
			(layer "F.SilkS")
		)
		(fp_line
			(start 0.7874 -0.4064)
			(end 0.7874 0.4064)
			(stroke
				(width 0.1524)
				(type default)
			)
			(layer "F.SilkS")
		)
		(fp_line
			(start -0.7874 0.4064)
			(end -0.7874 -0.4064)
			(stroke
				(width 0.1524)
				(type default)
			)
			(layer "F.SilkS")
		)
		(fp_line
			(start -0.7874 -0.4064)
			(end 0.7874 -0.4064)
			(stroke
				(width 0.1524)
				(type default)
			)
			(layer "F.SilkS")
		)
		(fp_line
			(start 0.67945 0.3048)
			(end 0.120396 0.3048)
			(stroke
				(width 0.1)
				(type default)
			)
			(layer "F.Fab")
		)
		(fp_line
			(start 0.67945 -0.3048)
			(end 0.67945 0.3048)
			(stroke
				(width 0.1)
				(type default)
			)
			(layer "F.Fab")
		)
		(fp_line
			(start 0.12065 -0.2794)
			(end 0.12065 -0.3048)
			(stroke
				(width 0.1)
				(type default)
			)
			(layer "F.Fab")
		)
		(fp_line
			(start 0.12065 -0.3048)
			(end 0.67945 -0.3048)
			(stroke
				(width 0.1)
				(type default)
			)
			(layer "F.Fab")
		)
		(fp_line
			(start 0.120396 0.3048)
			(end 0.120396 0.2794)
			(stroke
				(width 0.1)
				(type default)
			)
			(layer "F.Fab")
		)
		(fp_line
			(start 0.120396 0.2794)
			(end -0.12065 0.2794)
			(stroke
				(width 0.1)
				(type default)
			)
			(layer "F.Fab")
		)
		(fp_line
			(start -0.12065 0.3048)
			(end -0.67945 0.3048)
			(stroke
				(width 0.1)
				(type default)
			)
			(layer "F.Fab")
		)
		(fp_line
			(start -0.12065 0.2794)
			(end -0.12065 0.3048)
			(stroke
				(width 0.1)
				(type default)
			)
			(layer "F.Fab")
		)
		(fp_line
			(start -0.12065 -0.2794)
			(end 0.12065 -0.2794)
			(stroke
				(width 0.1)
				(type default)
			)
			(layer "F.Fab")
		)
		(fp_line
			(start -0.12065 -0.305054)
			(end -0.12065 -0.2794)
			(stroke
				(width 0.1)
				(type default)
			)
			(layer "F.Fab")
		)
		(fp_line
			(start -0.67945 0.3048)
			(end -0.67945 -0.305054)
			(stroke
				(width 0.1)
				(type default)
			)
			(layer "F.Fab")
		)
		(fp_line
			(start -0.67945 -0.305054)
			(end -0.12065 -0.305054)
			(stroke
				(width 0.1)
				(type default)
			)
			(layer "F.Fab")
		)
		(pad "1" smd circle
			(at -0.40005 0 180)
			(size 0 0)
			(layers "F.Cu" "F.Mask" "F.Paste")
			(net "P3V3_AUX")
		)
		(pad "2" smd circle
			(at 0.40005 0 180)
			(size 0 0)
			(layers "F.Cu" "F.Mask" "F.Paste")
			(net "PWRGD_P12V_SSD4_D")
		)
	)
	(footprint ""
		(layer "F.Cu")
		(at 314.861448 -144.396714 180)
		(property "Reference" "C436"
			(at 0 0 180)
			(layer "F.SilkS")
			(hide yes)
			(effects
				(font
					(size 1.27 1.27)
				)
			)
		)
		(property "Value" ""
			(at 0 0 180)
			(layer "F.Fab")
			(effects
				(font
					(size 1.27 1.27)
				)
			)
		)
		(duplicate_pad_numbers_are_jumpers no)
		(fp_line
			(start 0.299974 0.150114)
			(end -0.299974 0.150114)
			(stroke
				(width 0.1)
				(type default)
			)
			(layer "F.Fab")
		)
		(fp_line
			(start 0.299974 -0.150114)
			(end 0.299974 0.150114)
			(stroke
				(width 0.1)
				(type default)
			)
			(layer "F.Fab")
		)
		(fp_line
			(start -0.299974 0.150114)
			(end -0.299974 -0.150114)
			(stroke
				(width 0.1)
				(type default)
			)
			(layer "F.Fab")
		)
		(fp_line
			(start -0.299974 -0.150114)
			(end 0.299974 -0.150114)
			(stroke
				(width 0.1)
				(type default)
			)
			(layer "F.Fab")
		)
		(pad "1" smd rect
			(at -0.2667 0 180)
			(size 0.3048 0.381)
			(layers "F.Cu" "F.Mask" "F.Paste")
			(net "P5E_PEX2_STN0_TX_DN<9>")
		)
		(pad "2" smd rect
			(at 0.2667 0 180)
			(size 0.3048 0.381)
			(layers "F.Cu" "F.Mask" "F.Paste")
			(net "P5E_PEX2_STN0_TX_C_DN<9>")
		)
	)
	(footprint ""
		(layer "F.Cu")
		(at 151.209248 -453.294496)
		(property "Reference" "X21"
			(at -0.1778 -1.92913 0)
			(unlocked yes)
			(layer "F.SilkS")
			(effects
				(font
					(size 0.7874 0.5842)
					(thickness 0.1524)
				)
				(justify left)
			)
		)
		(property "Value" ""
			(at 0 0 0)
			(layer "F.Fab")
			(effects
				(font
					(size 1.27 1.27)
				)
			)
		)
		(property "Device Type" "TP_TDR_4P_FTS_MPKT4_H025P0200_IO_TP15_TP_TDR_4P_DIP"
			(at 1.30175 1.27 90)
			(unlocked yes)
			(layer "F.Fab")
			(hide yes)
			(effects
				(font
					(size 0.635 0.4064)
					(thickness 0.1524)
				)
			)
		)
		(property "User Part Number" "TP15"
			(at 1.30175 1.27 90)
			(unlocked yes)
			(layer "Cmts.User")
			(hide yes)
			(effects
				(font
					(size 0.635 0.4064)
					(thickness 0.1524)
				)
			)
		)
		(duplicate_pad_numbers_are_jumpers no)
		(fp_line
			(start 0 -1.27)
			(end 0 -0.635)
			(stroke
				(width 0.1524)
				(type default)
			)
			(layer "F.SilkS")
		)
		(fp_line
			(start 0 0.635)
			(end 0 1.905)
			(stroke
				(width 0.1524)
				(type default)
			)
			(layer "F.SilkS")
		)
		(fp_line
			(start 0 3.175)
			(end 0 3.81)
			(stroke
				(width 0.1524)
				(type default)
			)
			(layer "F.SilkS")
		)
		(fp_line
			(start 0 3.81)
			(end 2.54 3.81)
			(stroke
				(width 0.1524)
				(type default)
			)
			(layer "F.SilkS")
		)
		(fp_line
			(start 2.54 -1.27)
			(end 0 -1.27)
			(stroke
				(width 0.1524)
				(type default)
			)
			(layer "F.SilkS")
		)
		(fp_line
			(start 2.54 -1.1303)
			(end 2.54 -1.27)
			(stroke
				(width 0.1524)
				(type default)
			)
			(layer "F.SilkS")
		)
		(fp_line
			(start 2.54 1.4097)
			(end 2.54 1.1303)
			(stroke
				(width 0.1524)
				(type default)
			)
			(layer "F.SilkS")
		)
		(fp_line
			(start 2.54 3.81)
			(end 2.54 3.6703)
			(stroke
				(width 0.1524)
				(type default)
			)
			(layer "F.SilkS")
		)
		(fp_poly
			(pts
				(xy -0.761746 0) (xy -2.285746 -0.762) (xy -2.285746 0.762)
			)
			(stroke
				(width 0)
				(type default)
			)
			(fill yes)
			(layer "F.SilkS")
		)
		(fp_line
			(start 0 -1.27)
			(end 0 3.81)
			(stroke
				(width 0.1)
				(type default)
			)
			(layer "F.Fab")
		)
		(fp_line
			(start 0 3.81)
			(end 2.54 3.81)
			(stroke
				(width 0.1)
				(type default)
			)
			(layer "F.Fab")
		)
		(fp_line
			(start 2.54 -1.27)
			(end 0 -1.27)
			(stroke
				(width 0.1)
				(type default)
			)
			(layer "F.Fab")
		)
		(fp_line
			(start 2.54 3.81)
			(end 2.54 -1.27)
			(stroke
				(width 0.1)
				(type default)
			)
			(layer "F.Fab")
		)
		(fp_poly
			(pts
				(xy -0.761746 0) (xy -2.285746 -0.762) (xy -2.285746 0.762)
			)
			(stroke
				(width 0)
				(type default)
			)
			(fill yes)
			(layer "F.Fab")
		)
		(pad "1" thru_hole circle
			(at 0 0)
			(size 1.0033 1.0033)
			(drill 0.249936)
			(layers "*.Cu" "*.Mask")
			(remove_unused_layers no)
			(net "TDR_DIFF_85_IN3_DIN")
			(clearance 0.10795)
			(thermal_gap 0.10795)
			(padstack
				(mode front_inner_back)
				(layer "Inner"
					(shape circle)
					(size 0.8001 0.8001)
					(clearance 0.1524)
				)
				(layer "B.Cu"
					(shape circle)
					(size 1.0033 1.0033)
					(clearance 0.10795)
				)
			)
		)
		(pad "2" thru_hole circle
			(at 2.54 0)
			(size 1.9939 1.9939)
			(drill 0.249936)
			(layers "*.Cu" "*.Mask")
			(remove_unused_layers no)
			(net "COUPON_GND1")
			(clearance 0.10795)
			(thermal_gap 0.10795)
			(padstack
				(mode front_inner_back)
				(layer "Inner"
					(shape circle)
					(size 0.8001 0.8001)
					(clearance 0.1524)
				)
				(layer "B.Cu"
					(shape circle)
					(size 1.9939 1.9939)
					(clearance 0.10795)
				)
			)
		)
		(pad "3" thru_hole circle
			(at 2.54 2.54)
			(size 1.9939 1.9939)
			(drill 0.249936)
			(layers "*.Cu" "*.Mask")
			(remove_unused_layers no)
			(net "COUPON_GND1")
			(clearance 0.10795)
			(thermal_gap 0.10795)
			(padstack
				(mode front_inner_back)
				(layer "Inner"
					(shape circle)
					(size 0.8001 0.8001)
					(clearance 0.1524)
				)
				(layer "B.Cu"
					(shape circle)
					(size 1.9939 1.9939)
					(clearance 0.10795)
				)
			)
		)
		(pad "4" thru_hole circle
			(at 0 2.54)
			(size 1.0033 1.0033)
			(drill 0.249936)
			(layers "*.Cu" "*.Mask")
			(remove_unused_layers no)
			(net "TDR_DIFF_85_IN3_DIP")
			(clearance 0.10795)
			(thermal_gap 0.10795)
			(padstack
				(mode front_inner_back)
				(layer "Inner"
					(shape circle)
					(size 0.8001 0.8001)
					(clearance 0.1524)
				)
				(layer "B.Cu"
					(shape circle)
					(size 1.0033 1.0033)
					(clearance 0.10795)
				)
			)
		)
	)
	(footprint ""
		(layer "F.Cu")
		(at 256.542286 -252.356874 -90)
		(property "Reference" "R1365"
			(at 0 0 270)
			(layer "F.SilkS")
			(hide yes)
			(effects
				(font
					(size 1.27 1.27)
				)
			)
		)
		(property "Value" ""
			(at 0 0 270)
			(layer "F.Fab")
			(effects
				(font
					(size 1.27 1.27)
				)
			)
		)
		(duplicate_pad_numbers_are_jumpers no)
		(fp_line
			(start -0.7874 0.4064)
			(end -0.7874 -0.4064)
			(stroke
				(width 0.1524)
				(type default)
			)
			(layer "F.SilkS")
		)
		(fp_line
			(start 0.7874 0.4064)
			(end -0.7874 0.4064)
			(stroke
				(width 0.1524)
				(type default)
			)
			(layer "F.SilkS")
		)
		(fp_line
			(start -0.7874 -0.4064)
			(end 0.7874 -0.4064)
			(stroke
				(width 0.1524)
				(type default)
			)
			(layer "F.SilkS")
		)
		(fp_line
			(start 0.7874 -0.4064)
			(end 0.7874 0.4064)
			(stroke
				(width 0.1524)
				(type default)
			)
			(layer "F.SilkS")
		)
		(fp_line
			(start -0.67945 0.3048)
			(end -0.67945 -0.305054)
			(stroke
				(width 0.1)
				(type default)
			)
			(layer "F.Fab")
		)
		(fp_line
			(start -0.12065 0.3048)
			(end -0.67945 0.3048)
			(stroke
				(width 0.1)
				(type default)
			)
			(layer "F.Fab")
		)
		(fp_line
			(start 0.120396 0.3048)
			(end 0.120396 0.2794)
			(stroke
				(width 0.1)
				(type default)
			)
			(layer "F.Fab")
		)
		(fp_line
			(start 0.67945 0.3048)
			(end 0.120396 0.3048)
			(stroke
				(width 0.1)
				(type default)
			)
			(layer "F.Fab")
		)
		(fp_line
			(start -0.12065 0.2794)
			(end -0.12065 0.3048)
			(stroke
				(width 0.1)
				(type default)
			)
			(layer "F.Fab")
		)
		(fp_line
			(start 0.120396 0.2794)
			(end -0.12065 0.2794)
			(stroke
				(width 0.1)
				(type default)
			)
			(layer "F.Fab")
		)
		(fp_line
			(start -0.12065 -0.2794)
			(end 0.12065 -0.2794)
			(stroke
				(width 0.1)
				(type default)
			)
			(layer "F.Fab")
		)
		(fp_line
			(start 0.12065 -0.2794)
			(end 0.12065 -0.3048)
			(stroke
				(width 0.1)
				(type default)
			)
			(layer "F.Fab")
		)
		(fp_line
			(start 0.12065 -0.3048)
			(end 0.67945 -0.3048)
			(stroke
				(width 0.1)
				(type default)
			)
			(layer "F.Fab")
		)
		(fp_line
			(start 0.67945 -0.3048)
			(end 0.67945 0.3048)
			(stroke
				(width 0.1)
				(type default)
			)
			(layer "F.Fab")
		)
		(fp_line
			(start -0.67945 -0.305054)
			(end -0.12065 -0.305054)
			(stroke
				(width 0.1)
				(type default)
			)
			(layer "F.Fab")
		)
		(fp_line
			(start -0.12065 -0.305054)
			(end -0.12065 -0.2794)
			(stroke
				(width 0.1)
				(type default)
			)
			(layer "F.Fab")
		)
		(pad "1" smd circle
			(at -0.40005 0 270)
			(size 0 0)
			(layers "F.Cu" "F.Mask" "F.Paste")
			(net "GND")
		)
		(pad "2" smd circle
			(at 0.40005 0 270)
			(size 0 0)
			(layers "F.Cu" "F.Mask" "F.Paste")
			(net "PEX2_MODE_SEL9")
		)
	)
	(footprint ""
		(layer "F.Cu")
		(at 127.381508 -343.952322 90)
		(property "Reference" "C370"
			(at 0 0 90)
			(layer "F.SilkS")
			(hide yes)
			(effects
				(font
					(size 1.27 1.27)
				)
			)
		)
		(property "Value" ""
			(at 0 0 90)
			(layer "F.Fab")
			(effects
				(font
					(size 1.27 1.27)
				)
			)
		)
		(duplicate_pad_numbers_are_jumpers no)
		(fp_line
			(start 0.299974 -0.150114)
			(end 0.299974 0.150114)
			(stroke
				(width 0.1)
				(type default)
			)
			(layer "F.Fab")
		)
		(fp_line
			(start -0.299974 -0.150114)
			(end 0.299974 -0.150114)
			(stroke
				(width 0.1)
				(type default)
			)
			(layer "F.Fab")
		)
		(fp_line
			(start 0.299974 0.150114)
			(end -0.299974 0.150114)
			(stroke
				(width 0.1)
				(type default)
			)
			(layer "F.Fab")
		)
		(fp_line
			(start -0.299974 0.150114)
			(end -0.299974 -0.150114)
			(stroke
				(width 0.1)
				(type default)
			)
			(layer "F.Fab")
		)
		(pad "1" smd rect
			(at -0.2667 0 90)
			(size 0.3048 0.381)
			(layers "F.Cu" "F.Mask" "F.Paste")
			(net "P5E_PEX1_STN6_TX_DP<96>")
		)
		(pad "2" smd rect
			(at 0.2667 0 90)
			(size 0.3048 0.381)
			(layers "F.Cu" "F.Mask" "F.Paste")
			(net "P5E_PEX1_STN6_TX_C_DP<96>")
		)
	)
	(footprint ""
		(layer "F.Cu")
		(at 166.374064 -26.31186 -90)
		(property "Reference" "U403"
			(at -0.10414 -2.334006 90)
			(unlocked yes)
			(layer "F.SilkS")
			(effects
				(font
					(size 0.7874 0.5842)
					(thickness 0.1524)
				)
			)
		)
		(property "Value" ""
			(at 0 0 270)
			(layer "F.Fab")
			(effects
				(font
					(size 1.27 1.27)
				)
			)
		)
		(duplicate_pad_numbers_are_jumpers no)
		(fp_line
			(start -1.949958 1.610106)
			(end -1.949958 -1.610106)
			(stroke
				(width 0.1524)
				(type default)
			)
			(layer "F.SilkS")
		)
		(fp_line
			(start 1.949958 1.610106)
			(end -1.949958 1.610106)
			(stroke
				(width 0.1524)
				(type default)
			)
			(layer "F.SilkS")
		)
		(fp_line
			(start 1.949958 -1.560068)
			(end 1.949958 1.610106)
			(stroke
				(width 0.1524)
				(type default)
			)
			(layer "F.SilkS")
		)
		(fp_line
			(start -1.949958 -1.610106)
			(end 1.949958 -1.610106)
			(stroke
				(width 0.1524)
				(type default)
			)
			(layer "F.SilkS")
		)
		(fp_line
			(start -0.750062 1.560068)
			(end -0.750062 -1.560068)
			(stroke
				(width 0.1)
				(type default)
			)
			(layer "F.Fab")
		)
		(fp_line
			(start 0.750062 1.560068)
			(end -0.750062 1.560068)
			(stroke
				(width 0.1)
				(type default)
			)
			(layer "F.Fab")
		)
		(fp_line
			(start -0.750062 -1.560068)
			(end 0.750062 -1.560068)
			(stroke
				(width 0.1)
				(type default)
			)
			(layer "F.Fab")
		)
		(fp_line
			(start 0.750062 -1.560068)
			(end 0.750062 1.560068)
			(stroke
				(width 0.1)
				(type default)
			)
			(layer "F.Fab")
		)
		(pad "D" smd rect
			(at 1.100074 0 180)
			(size 1.016 1.4224)
			(layers "F.Cu" "F.Mask" "F.Paste")
			(net "SSD5_LED_ISO_N")
		)
		(pad "G" smd rect
			(at -1.100074 -0.94996 180)
			(size 1.016 1.4224)
			(layers "F.Cu" "F.Mask" "F.Paste")
			(net "SSD5_LED_R")
		)
		(pad "S" smd rect
			(at -1.100074 0.94996 180)
			(size 1.016 1.4224)
			(layers "F.Cu" "F.Mask" "F.Paste")
			(net "GND")
		)
	)
)
